# BASEBOARD_FAB2 (Tioga Pass) — schematic netlist excerpt (pin names and nets, part order shuffled) for the footprints in the layout excerpt that follows; sources: Cadence DE-HDL packaged netlist, KiCad conversion of Wiwynn_Tioga_Pass_MB.brd

C1D21  CAP_A  0.1UF 16V 10% X7R  pkg 0402V  page 199 : A = A_HSC_PSET ; B = AGND_HSC
C4C3  CAP_A  1.0UF 6.3V 10% X6S  pkg 0402V  page 96 : A = P3V3_STBY ; B = GND
R7W9  RES  0.0 5% CHIP  pkg 0402  page 118 : A = FM_CPU0_RC_ERROR_N ; B = FM_CPU0_RC_ERROR_R_N

(kicad_pcb
	(version 20260206)
	(generator "pcbnew")
	(generator_version "10.0")
	(general
		(thickness 1.6)
		(legacy_teardrops no)
	)
	(paper "A4")
	(title_block
		(title "Wiwynn_Tioga_Pass_MB.brd")
		(comment 1 "Tioga Pass / footprints 541-543 of 4770")
	)
	(layers
		(0 "F.Cu" signal "TOP")
		(4 "In1.Cu" signal "L2GND")
		(6 "In2.Cu" signal "L3")
		(8 "In3.Cu" signal "L4GND")
		(10 "In4.Cu" signal "L5")
		(12 "In5.Cu" signal "L6GND")
		(14 "In6.Cu" signal "L7VCC")
		(16 "In7.Cu" signal "L8VCC")
		(18 "In8.Cu" signal "L9GND")
		(20 "In9.Cu" signal "L10")
		(22 "In10.Cu" signal "L11GND")
		(24 "In11.Cu" signal "L12")
		(26 "In12.Cu" signal "L13GND")
		(2 "B.Cu" signal "BOTTOM")
		(9 "F.Adhes" user "F.Adhesive")
		(11 "B.Adhes" user "B.Adhesive")
		(13 "F.Paste" user "Package Geometry/Pastemask Top")
		(15 "B.Paste" user "Package Geometry/Pastemask Bottom")
		(5 "F.SilkS" user "Ref Des/Silkscreen Top")
		(7 "B.SilkS" user "Ref Des/Silkscreen Bottom")
		(1 "F.Mask" user "Board Geometry/Soldermask Top")
		(3 "B.Mask" user "Board Geometry/Soldermask Bottom")
		(17 "Dwgs.User" user "User.Drawings")
		(19 "Cmts.User" user "User.Comments")
		(21 "Eco1.User" user "User.Eco1")
		(23 "Eco2.User" user "User.Eco2")
		(25 "Edge.Cuts" user "Board Geometry/Outline")
		(27 "Margin" user)
		(31 "F.CrtYd" user "Package Geometry/Place Bound Top")
		(29 "B.CrtYd" user "Package Geometry/Place Bound Bottom")
		(35 "F.Fab" user "Ref Des/Assembly Top")
		(33 "B.Fab" user "Ref Des/Assembly Bottom")
	)
	(footprint ""
		(layer "F.Cu")
		(at 370.967 -99.695)
		(property "Reference" "R7W9"
			(at -0.8382 -0.67818 0)
			(unlocked yes)
			(layer "F.SilkS")
			(effects
				(font
					(size 0.4064 0.254)
					(thickness 0.1524)
				)
				(justify left)
			)
		)
		(property "Value" ""
			(at 0 0 0)
			(layer "F.Fab")
			(effects
				(font
					(size 1.27 1.27)
				)
			)
		)
		(duplicate_pad_numbers_are_jumpers no)
		(fp_poly
			(pts
				(xy -0.2794 -0.1016) (xy 0.2794 -0.1016) (xy 0.2794 0.9906) (xy -0.2794 0.9906)
			)
			(stroke
				(width 0)
				(type default)
			)
			(fill no)
			(layer "F.CrtYd")
		)
		(fp_line
			(start -0.2794 -0.1016)
			(end -0.2794 0.9906)
			(stroke
				(width 0.1)
				(type default)
			)
			(layer "F.Fab")
		)
		(fp_line
			(start -0.2794 0.9906)
			(end 0.2794 0.9906)
			(stroke
				(width 0.1)
				(type default)
			)
			(layer "F.Fab")
		)
		(fp_line
			(start 0.2794 -0.1016)
			(end -0.2794 -0.1016)
			(stroke
				(width 0.1)
				(type default)
			)
			(layer "F.Fab")
		)
		(fp_line
			(start 0.2794 0.9906)
			(end 0.2794 -0.1016)
			(stroke
				(width 0.1)
				(type default)
			)
			(layer "F.Fab")
		)
		(pad "1" smd rect
			(at 0 0)
			(size 0.508 0.508)
			(layers "F.Cu" "F.Mask" "F.Paste")
			(net "FM_CPU0_RC_ERROR_N")
		)
		(pad "2" smd rect
			(at 0 0.889)
			(size 0.508 0.508)
			(layers "F.Cu" "F.Mask" "F.Paste")
			(net "FM_CPU0_RC_ERROR_R_N")
		)
		(zone
			(layer "F.Cu")
			(hatch none 0.5)
			(connect_pads
				(clearance 0)
			)
			(min_thickness 0.25)
			(keepout
				(tracks allowed)
				(vias not_allowed)
				(pads allowed)
				(copperpour not_allowed)
				(footprints allowed)
			)
			(placement
				(enabled no)
				(sheetname "")
			)
			(fill
				(thermal_gap 0.5)
				(thermal_bridge_width 0.5)
				(island_removal_mode 0)
			)
			(polygon
				(pts
					(xy 370.713 -99.441) (xy 371.221 -99.441) (xy 371.221 -99.06) (xy 370.713 -99.06)
				)
			)
		)
		(zone
			(layer "F.Cu")
			(hatch none 0.5)
			(connect_pads
				(clearance 0)
			)
			(min_thickness 0.25)
			(keepout
				(tracks not_allowed)
				(vias allowed)
				(pads allowed)
				(copperpour not_allowed)
				(footprints allowed)
			)
			(placement
				(enabled no)
				(sheetname "")
			)
			(fill
				(thermal_gap 0.5)
				(thermal_bridge_width 0.5)
				(island_removal_mode 0)
			)
			(polygon
				(pts
					(xy 370.713 -99.06) (xy 371.221 -99.06) (xy 371.221 -99.441) (xy 370.713 -99.441)
				)
			)
		)
	)
	(footprint ""
		(layer "F.Cu")
		(at 22.225 -71.6788 90)
		(property "Reference" "C1D21"
			(at 0 0 90)
			(layer "F.SilkS")
			(hide yes)
			(effects
				(font
					(size 1.27 1.27)
				)
			)
		)
		(property "Value" ""
			(at 0 0 90)
			(layer "F.Fab")
			(effects
				(font
					(size 1.27 1.27)
				)
			)
		)
		(duplicate_pad_numbers_are_jumpers no)
		(fp_poly
			(pts
				(xy 0.3048 -0.1016) (xy 0.3048 0.9906) (xy -0.3048 0.9906) (xy -0.3048 -0.1016)
			)
			(stroke
				(width 0)
				(type default)
			)
			(fill no)
			(layer "F.CrtYd")
		)
		(fp_line
			(start 0.3048 -0.1016)
			(end -0.3048 -0.1016)
			(stroke
				(width 0.1)
				(type default)
			)
			(layer "F.Fab")
		)
		(fp_line
			(start -0.3048 -0.1016)
			(end -0.3048 0.9906)
			(stroke
				(width 0.1)
				(type default)
			)
			(layer "F.Fab")
		)
		(fp_line
			(start 0.3048 0.9906)
			(end 0.3048 -0.1016)
			(stroke
				(width 0.1)
				(type default)
			)
			(layer "F.Fab")
		)
		(fp_line
			(start -0.3048 0.9906)
			(end 0.3048 0.9906)
			(stroke
				(width 0.1)
				(type default)
			)
			(layer "F.Fab")
		)
		(pad "1" smd rect
			(at 0 0 90)
			(size 0.508 0.508)
			(layers "F.Cu" "F.Mask" "F.Paste")
			(net "A_HSC_PSET")
		)
		(pad "2" smd rect
			(at 0 0.889 90)
			(size 0.508 0.508)
			(layers "F.Cu" "F.Mask" "F.Paste")
			(net "AGND_HSC")
		)
		(zone
			(layer "F.Cu")
			(hatch none 0.5)
			(connect_pads
				(clearance 0)
			)
			(min_thickness 0.25)
			(keepout
				(tracks allowed)
				(vias not_allowed)
				(pads allowed)
				(copperpour not_allowed)
				(footprints allowed)
			)
			(placement
				(enabled no)
				(sheetname "")
			)
			(fill
				(thermal_gap 0.5)
				(thermal_bridge_width 0.5)
				(island_removal_mode 0)
			)
			(polygon
				(pts
					(xy 22.479 -71.4248) (xy 22.479 -71.9328) (xy 22.86 -71.9328) (xy 22.86 -71.4248)
				)
			)
		)
		(zone
			(layer "F.Cu")
			(hatch none 0.5)
			(connect_pads
				(clearance 0)
			)
			(min_thickness 0.25)
			(keepout
				(tracks not_allowed)
				(vias allowed)
				(pads allowed)
				(copperpour not_allowed)
				(footprints allowed)
			)
			(placement
				(enabled no)
				(sheetname "")
			)
			(fill
				(thermal_gap 0.5)
				(thermal_bridge_width 0.5)
				(island_removal_mode 0)
			)
			(polygon
				(pts
					(xy 22.86 -71.4248) (xy 22.86 -71.9328) (xy 22.479 -71.9328) (xy 22.479 -71.4248)
				)
			)
		)
	)
	(footprint ""
		(layer "F.Cu")
		(at 173.5836 -104.4448 180)
		(property "Reference" "C4C3"
			(at 0 0 180)
			(layer "F.SilkS")
			(hide yes)
			(effects
				(font
					(size 1.27 1.27)
				)
			)
		)
		(property "Value" ""
			(at 0 0 180)
			(layer "F.Fab")
			(effects
				(font
					(size 1.27 1.27)
				)
			)
		)
		(duplicate_pad_numbers_are_jumpers no)
		(fp_poly
			(pts
				(xy 0.3048 -0.1016) (xy 0.3048 0.9906) (xy -0.3048 0.9906) (xy -0.3048 -0.1016)
			)
			(stroke
				(width 0)
				(type default)
			)
			(fill no)
			(layer "F.CrtYd")
		)
		(fp_line
			(start 0.3048 0.9906)
			(end 0.3048 -0.1016)
			(stroke
				(width 0.1)
				(type default)
			)
			(layer "F.Fab")
		)
		(fp_line
			(start 0.3048 -0.1016)
			(end -0.3048 -0.1016)
			(stroke
				(width 0.1)
				(type default)
			)
			(layer "F.Fab")
		)
		(fp_line
			(start -0.3048 0.9906)
			(end 0.3048 0.9906)
			(stroke
				(width 0.1)
				(type default)
			)
			(layer "F.Fab")
		)
		(fp_line
			(start -0.3048 -0.1016)
			(end -0.3048 0.9906)
			(stroke
				(width 0.1)
				(type default)
			)
			(layer "F.Fab")
		)
		(pad "1" smd rect
			(at 0 0 180)
			(size 0.508 0.508)
			(layers "F.Cu" "F.Mask" "F.Paste")
			(net "P3V3_STBY")
		)
		(pad "2" smd rect
			(at 0 0.889 180)
			(size 0.508 0.508)
			(layers "F.Cu" "F.Mask" "F.Paste")
			(net "GND")
		)
		(zone
			(layer "F.Cu")
			(hatch none 0.5)
			(connect_pads
				(clearance 0)
			)
			(min_thickness 0.25)
			(keepout
				(tracks not_allowed)
				(vias allowed)
				(pads allowed)
				(copperpour not_allowed)
				(footprints allowed)
			)
			(placement
				(enabled no)
				(sheetname "")
			)
			(fill
				(thermal_gap 0.5)
				(thermal_bridge_width 0.5)
				(island_removal_mode 0)
			)
			(polygon
				(pts
					(xy 173.8376 -105.0798) (xy 173.3296 -105.0798) (xy 173.3296 -104.6988) (xy 173.8376 -104.6988)
				)
			)
		)
		(zone
			(layer "F.Cu")
			(hatch none 0.5)
			(connect_pads
				(clearance 0)
			)
			(min_thickness 0.25)
			(keepout
				(tracks allowed)
				(vias not_allowed)
				(pads allowed)
				(copperpour not_allowed)
				(footprints allowed)
			)
			(placement
				(enabled no)
				(sheetname "")
			)
			(fill
				(thermal_gap 0.5)
				(thermal_bridge_width 0.5)
				(island_removal_mode 0)
			)
			(polygon
				(pts
					(xy 173.8376 -104.6988) (xy 173.3296 -104.6988) (xy 173.3296 -105.0798) (xy 173.8376 -105.0798)
				)
			)
		)
	)
)
